# S9S_MB_2U (Grand Teton) — schematic netlist excerpt (pin names and nets, part order shuffled) for the footprints in the layout excerpt that follows; sources: Cadence DE-HDL packaged netlist, KiCad conversion of 03242023_DA0F0TMBIJ0_F0T_Motherboard_J_brd_V01_OCP.brd

PJP1  CONN3_210HP1030BR1  CONN3_210-HP1-030BR1 IO  pkg HEADER1X3XG  page 266
  \1\  = SMB_VR_3V3AUX_SCL_R3
  \2\  = GND
  \3\  = SMB_VR_3V3AUX_SDA_R3

H28  HOLE  EMPTY  pkg TH  page 311 : \1\ = NC

(kicad_pcb
	(version 20260206)
	(generator "pcbnew")
	(generator_version "10.0")
	(general
		(thickness 1.6)
		(legacy_teardrops no)
	)
	(paper "A4")
	(title_block
		(title "03242023_DA0F0TMBIJ0_F0T_Motherboard_J_brd_V01_OCP.brd")
		(comment 1 "Grand Teton / footprints 1045-1046 of 6105")
	)
	(layers
		(0 "F.Cu" signal "TOP")
		(4 "In1.Cu" signal "GND")
		(6 "In2.Cu" signal "IN1")
		(8 "In3.Cu" signal "GND1")
		(10 "In4.Cu" signal "IN2")
		(12 "In5.Cu" signal "GND2")
		(14 "In6.Cu" signal "IN3")
		(16 "In7.Cu" signal "GND3")
		(18 "In8.Cu" signal "VCC")
		(20 "In9.Cu" signal "VCC1")
		(22 "In10.Cu" signal "GND4")
		(24 "In11.Cu" signal "IN4")
		(26 "In12.Cu" signal "GND5")
		(28 "In13.Cu" signal "IN5")
		(30 "In14.Cu" signal "GND6")
		(32 "In15.Cu" signal "IN6")
		(34 "In16.Cu" signal "GND7")
		(2 "B.Cu" signal "BOTTOM")
		(9 "F.Adhes" user "F.Adhesive")
		(11 "B.Adhes" user "B.Adhesive")
		(13 "F.Paste" user "Package Geometry/Pastemask Top")
		(15 "B.Paste" user "Package Geometry/Pastemask Bottom")
		(5 "F.SilkS" user "Ref Des/Silkscreen Top")
		(7 "B.SilkS" user "Ref Des/Silkscreen Bottom")
		(1 "F.Mask" user "Board Geometry/Soldermask Top")
		(3 "B.Mask" user "Board Geometry/Soldermask Bottom")
		(17 "Dwgs.User" user "User.Drawings")
		(19 "Cmts.User" user "User.Comments")
		(21 "Eco1.User" user "User.Eco1")
		(23 "Eco2.User" user "User.Eco2")
		(25 "Edge.Cuts" user "Board Geometry/Outline")
		(27 "Margin" user)
		(31 "F.CrtYd" user "Package Geometry/Place Bound Top")
		(29 "B.CrtYd" user "Package Geometry/Place Bound Bottom")
		(35 "F.Fab" user "Ref Des/Assembly Top")
		(33 "B.Fab" user "Ref Des/Assembly Bottom")
	)
	(footprint ""
		(layer "F.Cu")
		(at 139.505944 -366.066578 90)
		(property "Reference" "PJP1"
			(at 3.7973 4.352036 0)
			(unlocked yes)
			(layer "F.SilkS")
			(effects
				(font
					(size 0.7874 0.5842)
					(thickness 0.1524)
				)
				(justify left)
			)
		)
		(property "Value" ""
			(at 0 0 90)
			(layer "F.Fab")
			(effects
				(font
					(size 1.27 1.27)
				)
			)
		)
		(duplicate_pad_numbers_are_jumpers no)
		(fp_line
			(start 1.249934 -1.320038)
			(end 1.249934 6.400038)
			(stroke
				(width 0.1524)
				(type default)
			)
			(layer "F.SilkS")
		)
		(fp_line
			(start -1.249934 -1.320038)
			(end 1.249934 -1.320038)
			(stroke
				(width 0.1524)
				(type default)
			)
			(layer "F.SilkS")
		)
		(fp_line
			(start 1.249934 6.400038)
			(end -1.249934 6.400038)
			(stroke
				(width 0.1524)
				(type default)
			)
			(layer "F.SilkS")
		)
		(fp_line
			(start -1.249934 6.400038)
			(end -1.249934 -1.320038)
			(stroke
				(width 0.1524)
				(type default)
			)
			(layer "F.SilkS")
		)
		(fp_poly
			(pts
				(xy -1.668272 -0.08636) (xy -2.7813 0.470154) (xy -2.7813 -0.642874)
			)
			(stroke
				(width 0)
				(type default)
			)
			(fill yes)
			(layer "F.SilkS")
		)
		(fp_line
			(start 1.249934 -1.320038)
			(end 1.249934 6.400038)
			(stroke
				(width 0.1)
				(type default)
			)
			(layer "F.Fab")
		)
		(fp_line
			(start -1.249934 -1.320038)
			(end 1.249934 -1.320038)
			(stroke
				(width 0.1)
				(type default)
			)
			(layer "F.Fab")
		)
		(fp_line
			(start 1.249934 6.400038)
			(end -1.249934 6.400038)
			(stroke
				(width 0.1)
				(type default)
			)
			(layer "F.Fab")
		)
		(fp_line
			(start -1.249934 6.400038)
			(end -1.249934 -1.320038)
			(stroke
				(width 0.1)
				(type default)
			)
			(layer "F.Fab")
		)
		(fp_poly
			(pts
				(xy -2.5654 -0.556514) (xy -1.452372 0) (xy -2.5654 0.556514)
			)
			(stroke
				(width 0)
				(type default)
			)
			(fill yes)
			(layer "F.Fab")
		)
		(fp_text user "3"
			(at -2.01676 5.393436 0)
			(unlocked yes)
			(layer "F.SilkS")
			(effects
				(font
					(size 0.7874 0.5842)
					(thickness 0.1524)
				)
			)
		)
		(fp_text user "1"
			(at -1.143 0.02667 90)
			(unlocked yes)
			(layer "B.SilkS")
			(effects
				(font
					(size 0.7874 0.5842)
					(thickness 0.1524)
				)
				(justify mirror)
			)
		)
		(fp_text user "3"
			(at -1.1557 5.18287 90)
			(unlocked yes)
			(layer "B.SilkS")
			(effects
				(font
					(size 0.7874 0.5842)
					(thickness 0.1524)
				)
				(justify mirror)
			)
		)
		(fp_text user "1"
			(at -1.143 0.02667 90)
			(unlocked yes)
			(layer "B.Fab")
			(effects
				(font
					(size 0.7874 0.5842)
					(thickness 0.1524)
				)
				(justify mirror)
			)
		)
		(fp_text user "3"
			(at -1.1557 5.18287 90)
			(unlocked yes)
			(layer "B.Fab")
			(effects
				(font
					(size 0.7874 0.5842)
					(thickness 0.1524)
				)
				(justify mirror)
			)
		)
		(fp_text user "3"
			(at -1.778 5.13207 90)
			(unlocked yes)
			(layer "F.Fab")
			(effects
				(font
					(size 0.7874 0.5842)
					(thickness 0.1524)
				)
			)
		)
		(pad "1" thru_hole rect
			(at 0 0 90)
			(size 1.5494 1.5494)
			(drill 1.0414)
			(layers "*.Cu" "*.Mask")
			(remove_unused_layers no)
			(net "SMB_VR_3V3AUX_SCL_R3")
			(clearance 0)
			(padstack
				(mode front_inner_back)
				(layer "Inner"
					(shape circle)
					(size 1.5494 1.5494)
					(clearance 0)
				)
				(layer "B.Cu"
					(shape rect)
					(size 1.5494 1.5494)
					(clearance 0)
				)
			)
		)
		(pad "2" thru_hole circle
			(at 0 2.54 90)
			(size 1.5494 1.5494)
			(drill 1.0414)
			(layers "*.Cu" "*.Mask")
			(remove_unused_layers no)
			(net "GND")
			(clearance 0)
		)
		(pad "3" thru_hole circle
			(at 0 5.08 90)
			(size 1.5494 1.5494)
			(drill 1.0414)
			(layers "*.Cu" "*.Mask")
			(remove_unused_layers no)
			(net "SMB_VR_3V3AUX_SDA_R3")
			(clearance 0)
		)
	)
	(footprint ""
		(layer "F.Cu")
		(at 12.51712 -85.700108)
		(property "Reference" "H28"
			(at -5.94614 -2.116328 0)
			(unlocked yes)
			(layer "F.SilkS")
			(effects
				(font
					(size 0.7874 0.5842)
					(thickness 0.1524)
				)
				(justify left)
			)
		)
		(property "Value" ""
			(at 0 0 0)
			(layer "F.Fab")
			(effects
				(font
					(size 1.27 1.27)
				)
			)
		)
		(duplicate_pad_numbers_are_jumpers no)
		(fp_circle
			(center 0 0)
			(end 2.4003 0)
			(stroke
				(width 0.1524)
				(type default)
			)
			(fill no)
			(layer "F.SilkS")
		)
		(fp_circle
			(center 0 0)
			(end 6.5913 0)
			(stroke
				(width 0.1524)
				(type default)
			)
			(fill no)
			(layer "B.SilkS")
		)
		(fp_circle
			(center 0 0)
			(end 6.5913 0)
			(stroke
				(width 0.1)
				(type default)
			)
			(fill no)
			(layer "B.Fab")
		)
		(fp_circle
			(center 0 0)
			(end 2.4003 0)
			(stroke
				(width 0.1)
				(type default)
			)
			(fill no)
			(layer "F.Fab")
		)
		(pad "" np_thru_hole circle
			(at 0 0)
			(size 3.175 3.175)
			(drill 3.175)
			(layers "*.Cu" "*.Mask")
			(clearance 0.381)
			(thermal_gap 0.381)
		)
		(zone
			(layers "F.Cu" "B.Cu" "In1.Cu" "In2.Cu" "In3.Cu" "In4.Cu" "In5.Cu" "In6.Cu"
				"In7.Cu" "In8.Cu" "In9.Cu" "In10.Cu" "In11.Cu" "In12.Cu" "In13.Cu" "In14.Cu"
				"In15.Cu" "In16.Cu"
			)
			(hatch none 0.5)
			(connect_pads
				(clearance 0)
			)
			(min_thickness 0.25)
			(keepout
				(tracks not_allowed)
				(vias allowed)
				(pads allowed)
				(copperpour not_allowed)
				(footprints allowed)
			)
			(placement
				(enabled no)
				(sheetname "")
			)
			(fill
				(thermal_gap 0.5)
				(thermal_bridge_width 0.5)
				(island_removal_mode 0)
			)
			(polygon
				(pts
					(arc
						(start 14.61262 -85.700108)
						(mid 10.42162 -85.700108)
						(end 14.61262 -85.700108)
					)
				)
			)
		)
	)
)
